# T6G (Grand Teton) — schematic netlist excerpt (pin names and nets, part order shuffled) for the footprints in the layout excerpt that follows; sources: Cadence DE-HDL packaged netlist, KiCad conversion of 04192023_DAF0TMB3IC0_F0TG_MB_C_brd_V02_OCP.brd

C175  Q_CAP  10UF 25V 10% X6S  pkg C0805  page 99 : A = P12V_MEM_CPU1 ; B = GND
R9273  Q_RES  0 5% CHIP  pkg 0402LF  page 28 : A = CLK_100M_CPU0_CLK04_R_DP ; B = CLK_100M_CPU0_CLK04_DP
C2537  Q_CAP  22UF 4V 20% X6S  pkg C0402  page 70 : A = PVDDCR_SOC_P0 ; B = GND

(kicad_pcb
	(version 20260206)
	(generator "pcbnew")
	(generator_version "10.0")
	(general
		(thickness 1.6)
		(legacy_teardrops no)
	)
	(paper "A4")
	(title_block
		(title "04192023_DAF0TMB3IC0_F0TG_MB_C_brd_V02_OCP.brd")
		(comment 1 "Grand Teton / footprints 5049-5051 of 8354")
	)
	(layers
		(0 "F.Cu" signal "TOP")
		(4 "In1.Cu" signal "GND")
		(6 "In2.Cu" signal "IN1")
		(8 "In3.Cu" signal "GND1")
		(10 "In4.Cu" signal "IN2")
		(12 "In5.Cu" signal "GND2")
		(14 "In6.Cu" signal "IN3")
		(16 "In7.Cu" signal "GND3")
		(18 "In8.Cu" signal "VCC")
		(20 "In9.Cu" signal "VCC1")
		(22 "In10.Cu" signal "GND4")
		(24 "In11.Cu" signal "IN4")
		(26 "In12.Cu" signal "GND5")
		(28 "In13.Cu" signal "IN5")
		(30 "In14.Cu" signal "GND6")
		(32 "In15.Cu" signal "IN6")
		(34 "In16.Cu" signal "GND7")
		(2 "B.Cu" signal "BOTTOM")
		(9 "F.Adhes" user "F.Adhesive")
		(11 "B.Adhes" user "B.Adhesive")
		(13 "F.Paste" user "Package Geometry/Pastemask Top")
		(15 "B.Paste" user "Package Geometry/Pastemask Bottom")
		(5 "F.SilkS" user "Ref Des/Silkscreen Top")
		(7 "B.SilkS" user "Ref Des/Silkscreen Bottom")
		(1 "F.Mask" user "Board Geometry/Soldermask Top")
		(3 "B.Mask" user "Board Geometry/Soldermask Bottom")
		(17 "Dwgs.User" user "User.Drawings")
		(19 "Cmts.User" user "User.Comments")
		(21 "Eco1.User" user "User.Eco1")
		(23 "Eco2.User" user "User.Eco2")
		(25 "Edge.Cuts" user "Board Geometry/Outline")
		(27 "Margin" user)
		(31 "F.CrtYd" user "Package Geometry/Place Bound Top")
		(29 "B.CrtYd" user "Package Geometry/Place Bound Bottom")
		(35 "F.Fab" user "Ref Des/Assembly Top")
		(33 "B.Fab" user "Ref Des/Assembly Bottom")
	)
	(footprint ""
		(layer "B.Cu")
		(at 47.784004 -192.66027 180)
		(property "Reference" "C175"
			(at 0 0 0)
			(layer "B.SilkS")
			(hide yes)
			(effects
				(font
					(size 1.27 1.27)
				)
				(justify mirror)
			)
		)
		(property "Value" ""
			(at 0 0 0)
			(layer "B.Fab")
			(effects
				(font
					(size 1.27 1.27)
				)
				(justify mirror)
			)
		)
		(duplicate_pad_numbers_are_jumpers no)
		(fp_line
			(start 1.524 0.762)
			(end 1.524 -0.762)
			(stroke
				(width 0.1524)
				(type default)
			)
			(layer "B.SilkS")
		)
		(fp_line
			(start 1.524 -0.762)
			(end -1.524 -0.762)
			(stroke
				(width 0.1524)
				(type default)
			)
			(layer "B.SilkS")
		)
		(fp_line
			(start -1.524 0.762)
			(end 1.524 0.762)
			(stroke
				(width 0.1524)
				(type default)
			)
			(layer "B.SilkS")
		)
		(fp_line
			(start -1.524 -0.762)
			(end -1.524 0.762)
			(stroke
				(width 0.1524)
				(type default)
			)
			(layer "B.SilkS")
		)
		(fp_line
			(start 1.1049 0.724916)
			(end -1.1049 0.724916)
			(stroke
				(width 0.1)
				(type default)
			)
			(layer "B.Fab")
		)
		(fp_line
			(start 1.1049 -0.724916)
			(end 1.1049 0.724916)
			(stroke
				(width 0.1)
				(type default)
			)
			(layer "B.Fab")
		)
		(fp_line
			(start -1.1049 0.724916)
			(end -1.1049 -0.724916)
			(stroke
				(width 0.1)
				(type default)
			)
			(layer "B.Fab")
		)
		(fp_line
			(start -1.1049 -0.724916)
			(end 1.1049 -0.724916)
			(stroke
				(width 0.1)
				(type default)
			)
			(layer "B.Fab")
		)
		(pad "1" smd rect
			(at 0.889 0 180)
			(size 1.016 1.27)
			(layers "B.Cu" "B.Mask" "B.Paste")
			(net "P12V_MEM_CPU1")
		)
		(pad "2" smd rect
			(at -0.889 0 180)
			(size 1.016 1.27)
			(layers "B.Cu" "B.Mask" "B.Paste")
			(net "GND")
		)
	)
	(footprint ""
		(layer "B.Cu")
		(at 374.487186 -214.523828 90)
		(property "Reference" "R9273"
			(at 0 0 90)
			(layer "B.SilkS")
			(hide yes)
			(effects
				(font
					(size 1.27 1.27)
				)
				(justify mirror)
			)
		)
		(property "Value" ""
			(at 0 0 90)
			(layer "B.Fab")
			(effects
				(font
					(size 1.27 1.27)
				)
				(justify mirror)
			)
		)
		(duplicate_pad_numbers_are_jumpers no)
		(fp_line
			(start 0.436372 -0.4064)
			(end -0.351028 -0.4064)
			(stroke
				(width 0.1524)
				(type default)
			)
			(layer "B.SilkS")
		)
		(fp_line
			(start -0.7874 0.035814)
			(end -0.7874 0.4064)
			(stroke
				(width 0.1524)
				(type default)
			)
			(layer "B.SilkS")
		)
		(fp_line
			(start 0.7874 0.4064)
			(end 0.7874 -0.014986)
			(stroke
				(width 0.1524)
				(type default)
			)
			(layer "B.SilkS")
		)
		(fp_line
			(start -0.7874 0.4064)
			(end 0.7874 0.4064)
			(stroke
				(width 0.1524)
				(type default)
			)
			(layer "B.SilkS")
		)
		(fp_line
			(start 0.67945 -0.305054)
			(end 0.12065 -0.305054)
			(stroke
				(width 0.1)
				(type default)
			)
			(layer "B.Fab")
		)
		(fp_line
			(start 0.12065 -0.305054)
			(end 0.12065 -0.2794)
			(stroke
				(width 0.1)
				(type default)
			)
			(layer "B.Fab")
		)
		(fp_line
			(start -0.12065 -0.3048)
			(end -0.67945 -0.3048)
			(stroke
				(width 0.1)
				(type default)
			)
			(layer "B.Fab")
		)
		(fp_line
			(start -0.67945 -0.3048)
			(end -0.67945 0.3048)
			(stroke
				(width 0.1)
				(type default)
			)
			(layer "B.Fab")
		)
		(fp_line
			(start 0.12065 -0.2794)
			(end -0.12065 -0.2794)
			(stroke
				(width 0.1)
				(type default)
			)
			(layer "B.Fab")
		)
		(fp_line
			(start -0.12065 -0.2794)
			(end -0.12065 -0.3048)
			(stroke
				(width 0.1)
				(type default)
			)
			(layer "B.Fab")
		)
		(fp_line
			(start 0.12065 0.2794)
			(end 0.12065 0.3048)
			(stroke
				(width 0.1)
				(type default)
			)
			(layer "B.Fab")
		)
		(fp_line
			(start -0.120396 0.2794)
			(end 0.12065 0.2794)
			(stroke
				(width 0.1)
				(type default)
			)
			(layer "B.Fab")
		)
		(fp_line
			(start 0.67945 0.3048)
			(end 0.67945 -0.305054)
			(stroke
				(width 0.1)
				(type default)
			)
			(layer "B.Fab")
		)
		(fp_line
			(start 0.12065 0.3048)
			(end 0.67945 0.3048)
			(stroke
				(width 0.1)
				(type default)
			)
			(layer "B.Fab")
		)
		(fp_line
			(start -0.120396 0.3048)
			(end -0.120396 0.2794)
			(stroke
				(width 0.1)
				(type default)
			)
			(layer "B.Fab")
		)
		(fp_line
			(start -0.67945 0.3048)
			(end -0.120396 0.3048)
			(stroke
				(width 0.1)
				(type default)
			)
			(layer "B.Fab")
		)
		(pad "1" smd circle
			(at 0.40005 0 270)
			(size 0 0)
			(layers "B.Cu" "B.Mask" "B.Paste")
			(net "CLK_100M_CPU0_CLK04_R_DP")
		)
		(pad "2" smd circle
			(at -0.40005 0 270)
			(size 0 0)
			(layers "B.Cu" "B.Mask" "B.Paste")
			(net "CLK_100M_CPU0_CLK04_DP")
		)
	)
	(footprint ""
		(layer "B.Cu")
		(at 369.62588 -258.830064)
		(property "Reference" "C2537"
			(at 0 0 0)
			(layer "B.SilkS")
			(hide yes)
			(effects
				(font
					(size 1.27 1.27)
				)
				(justify mirror)
			)
		)
		(property "Value" ""
			(at 0 0 0)
			(layer "B.Fab")
			(effects
				(font
					(size 1.27 1.27)
				)
				(justify mirror)
			)
		)
		(duplicate_pad_numbers_are_jumpers no)
		(fp_line
			(start -0.7874 -0.4064)
			(end -0.7874 0.4064)
			(stroke
				(width 0.1524)
				(type default)
			)
			(layer "B.SilkS")
		)
		(fp_line
			(start -0.7874 0.4064)
			(end 0.7874 0.4064)
			(stroke
				(width 0.1524)
				(type default)
			)
			(layer "B.SilkS")
		)
		(fp_line
			(start 0.7874 -0.4064)
			(end -0.7874 -0.4064)
			(stroke
				(width 0.1524)
				(type default)
			)
			(layer "B.SilkS")
		)
		(fp_line
			(start 0.7874 0.4064)
			(end 0.7874 -0.4064)
			(stroke
				(width 0.1524)
				(type default)
			)
			(layer "B.SilkS")
		)
		(fp_line
			(start -0.67945 -0.3048)
			(end -0.67945 0.3048)
			(stroke
				(width 0.1)
				(type default)
			)
			(layer "B.Fab")
		)
		(fp_line
			(start -0.67945 0.3048)
			(end -0.120396 0.3048)
			(stroke
				(width 0.1)
				(type default)
			)
			(layer "B.Fab")
		)
		(fp_line
			(start -0.12065 -0.3048)
			(end -0.67945 -0.3048)
			(stroke
				(width 0.1)
				(type default)
			)
			(layer "B.Fab")
		)
		(fp_line
			(start -0.12065 -0.2794)
			(end -0.12065 -0.3048)
			(stroke
				(width 0.1)
				(type default)
			)
			(layer "B.Fab")
		)
		(fp_line
			(start -0.120396 0.2794)
			(end 0.12065 0.2794)
			(stroke
				(width 0.1)
				(type default)
			)
			(layer "B.Fab")
		)
		(fp_line
			(start -0.120396 0.3048)
			(end -0.120396 0.2794)
			(stroke
				(width 0.1)
				(type default)
			)
			(layer "B.Fab")
		)
		(fp_line
			(start 0.12065 -0.305054)
			(end 0.12065 -0.2794)
			(stroke
				(width 0.1)
				(type default)
			)
			(layer "B.Fab")
		)
		(fp_line
			(start 0.12065 -0.2794)
			(end -0.12065 -0.2794)
			(stroke
				(width 0.1)
				(type default)
			)
			(layer "B.Fab")
		)
		(fp_line
			(start 0.12065 0.2794)
			(end 0.12065 0.3048)
			(stroke
				(width 0.1)
				(type default)
			)
			(layer "B.Fab")
		)
		(fp_line
			(start 0.12065 0.3048)
			(end 0.67945 0.3048)
			(stroke
				(width 0.1)
				(type default)
			)
			(layer "B.Fab")
		)
		(fp_line
			(start 0.67945 -0.305054)
			(end 0.12065 -0.305054)
			(stroke
				(width 0.1)
				(type default)
			)
			(layer "B.Fab")
		)
		(fp_line
			(start 0.67945 0.3048)
			(end 0.67945 -0.305054)
			(stroke
				(width 0.1)
				(type default)
			)
			(layer "B.Fab")
		)
		(pad "1" smd circle
			(at 0.40005 0 180)
			(size 0 0)
			(layers "B.Cu" "B.Mask" "B.Paste")
			(net "PVDDCR_SOC_P0")
		)
		(pad "2" smd circle
			(at -0.40005 0 180)
			(size 0 0)
			(layers "B.Cu" "B.Mask" "B.Paste")
			(net "GND")
		)
	)
)
